# TIMECARD (Time Appliance Project (Time Card)) — schematic netlist excerpt (pin names and nets, part order shuffled) for the footprints in the layout excerpt that follows; sources: Cadence DE-HDL packaged netlist, KiCad conversion of R4006-B0001-02_R01.brd

P2  CONN_HDR_2X4_F_S_SMT  SQW-104-01-F-D-VS-K-TR  pkg S_F_H_2X4_S_P0787_V1  page 22
  \1\  = XP5R0V_VCC_ANT
  \2\  = XP3R3V_GPS
  \3\  = GPS_UART_TXD
  \4\  = GPS_RST_N
  \5\  = GPS_UART_RXD
  \6\  = GPSTP1_OUT
  \7\  = GPSTP2_OUT
  \8\  = SG

C239  CAPACITOR  10UF 25V 20%  pkg SMC_0805R_H057  page 31 : \1\ = XP2R5V_FPGA ; \2\ = SG

(kicad_pcb
	(version 20260206)
	(generator "pcbnew")
	(generator_version "10.0")
	(general
		(thickness 1.6)
		(legacy_teardrops no)
	)
	(paper "A4")
	(title_block
		(title "timecard-production-celestica-r4006 — R4006-B0001-02_R01.brd")
		(comment 1 "Time Appliance Project (Time Card) / footprints 665-666 of 1113")
	)
	(layers
		(0 "F.Cu" signal "TOP")
		(4 "In1.Cu" signal "L02_GND1")
		(6 "In2.Cu" signal "L03_SIG1")
		(8 "In3.Cu" signal "L04_GND2")
		(10 "In4.Cu" signal "L05_VCC1")
		(12 "In5.Cu" signal "L06_VCC2")
		(14 "In6.Cu" signal "L07_GND3")
		(16 "In7.Cu" signal "L08_SIG2")
		(18 "In8.Cu" signal "L09_GND4")
		(2 "B.Cu" signal "BOTTOM")
		(9 "F.Adhes" user "F.Adhesive")
		(11 "B.Adhes" user "B.Adhesive")
		(13 "F.Paste" user "Package Geometry/Pastemask Top")
		(15 "B.Paste" user "Package Geometry/Pastemask Bottom")
		(5 "F.SilkS" user "Ref Des/Silkscreen Top")
		(7 "B.SilkS" user "Ref Des/Silkscreen Bottom")
		(1 "F.Mask" user "Board Geometry/Soldermask Top")
		(3 "B.Mask" user "Board Geometry/Soldermask Bottom")
		(17 "Dwgs.User" user "User.Drawings")
		(19 "Cmts.User" user "User.Comments")
		(21 "Eco1.User" user "User.Eco1")
		(23 "Eco2.User" user "User.Eco2")
		(25 "Edge.Cuts" user "Board Geometry/Outline")
		(27 "Margin" user)
		(31 "F.CrtYd" user "Package Geometry/Place Bound Top")
		(29 "B.CrtYd" user "Package Geometry/Place Bound Bottom")
		(35 "F.Fab" user "Ref Des/Assembly Top")
		(33 "B.Fab" user "Ref Des/Assembly Bottom")
	)
	(footprint ""
		(layer "F.Cu")
		(at 140.1318 -21.9202)
		(property "Reference" "C239"
			(at -3.2258 -1.02743 0)
			(unlocked yes)
			(layer "F.SilkS")
			(effects
				(font
					(size 0.7874 0.5842)
					(thickness 0.1524)
				)
			)
		)
		(property "Value" "VAL*"
			(at 0.0762 3.134106 0)
			(unlocked yes)
			(layer "F.Fab")
			(hide yes)
			(effects
				(font
					(size 0.7874 0.5842)
					(thickness 0.1524)
				)
			)
		)
		(property "Tolerance" "TOL*"
			(at 0.0762 4.048506 0)
			(unlocked yes)
			(layer "Cmts.User")
			(hide yes)
			(effects
				(font
					(size 0.7874 0.5842)
					(thickness 0.1524)
				)
			)
		)
		(property "User Part Number" "PARTNUM*"
			(at 0.1016 5.013706 0)
			(unlocked yes)
			(layer "Cmts.User")
			(hide yes)
			(effects
				(font
					(size 0.7874 0.5842)
					(thickness 0.1524)
				)
			)
		)
		(property "Device Type" "CAPACITOR-G107-0F106-EM,10UF,2A"
			(at 0.0508 2.194306 0)
			(unlocked yes)
			(layer "F.Fab")
			(hide yes)
			(effects
				(font
					(size 0.7874 0.5842)
					(thickness 0.1524)
				)
			)
		)
		(duplicate_pad_numbers_are_jumpers no)
		(fp_line
			(start -1.5748 -0.9398)
			(end -1.5748 0.9398)
			(stroke
				(width 0.1)
				(type default)
			)
			(layer "F.SilkS")
		)
		(fp_line
			(start -1.5748 0.9398)
			(end 1.5748 0.9398)
			(stroke
				(width 0.1)
				(type default)
			)
			(layer "F.SilkS")
		)
		(fp_line
			(start 1.5748 -0.9398)
			(end -1.5748 -0.9398)
			(stroke
				(width 0.1)
				(type default)
			)
			(layer "F.SilkS")
		)
		(fp_line
			(start 1.5748 0.9398)
			(end 1.5748 -0.9398)
			(stroke
				(width 0.1)
				(type default)
			)
			(layer "F.SilkS")
		)
		(fp_rect
			(start 1.5748 -0.9398)
			(end -1.5748 0.9398)
			(stroke
				(width 0)
				(type default)
			)
			(fill no)
			(layer "F.CrtYd")
		)
		(fp_line
			(start -1.016 -0.635)
			(end -1.016 0.635)
			(stroke
				(width 0.1)
				(type default)
			)
			(layer "F.Fab")
		)
		(fp_line
			(start -1.016 0.635)
			(end 1.016 0.635)
			(stroke
				(width 0.1)
				(type default)
			)
			(layer "F.Fab")
		)
		(fp_line
			(start 1.016 -0.635)
			(end -1.016 -0.635)
			(stroke
				(width 0.1)
				(type default)
			)
			(layer "F.Fab")
		)
		(fp_line
			(start 1.016 0.635)
			(end 1.016 -0.635)
			(stroke
				(width 0.1)
				(type default)
			)
			(layer "F.Fab")
		)
		(pad "1" smd rect
			(at -0.8382 0)
			(size 0.9652 1.3716)
			(layers "F.Cu" "F.Mask" "F.Paste")
			(net "XP2R5V_FPGA")
		)
		(pad "2" smd rect
			(at 0.8382 0)
			(size 0.9652 1.3716)
			(layers "F.Cu" "F.Mask" "F.Paste")
			(net "SG")
		)
		(zone
			(layer "F.Cu")
			(hatch none 0.5)
			(connect_pads
				(clearance 0)
			)
			(min_thickness 0.25)
			(keepout
				(tracks allowed)
				(vias not_allowed)
				(pads allowed)
				(copperpour not_allowed)
				(footprints allowed)
			)
			(placement
				(enabled no)
				(sheetname "")
			)
			(fill
				(thermal_gap 0.5)
				(thermal_bridge_width 0.5)
				(island_removal_mode 0)
			)
			(polygon
				(pts
					(xy 140.3604 -22.5552) (xy 139.9032 -22.5552) (xy 139.9032 -21.2852) (xy 140.3604 -21.2852)
				)
			)
		)
	)
	(footprint ""
		(layer "F.Cu")
		(at 123.215908 -96.270064 90)
		(property "Reference" "P2"
			(at -0.932434 -4.089908 0)
			(unlocked yes)
			(layer "F.SilkS")
			(effects
				(font
					(size 0.7874 0.5842)
					(thickness 0.1524)
				)
			)
		)
		(property "Value" ""
			(at 0 0 90)
			(layer "F.Fab")
			(effects
				(font
					(size 1.27 1.27)
				)
			)
		)
		(property "User Part Number" "PARTNUM*"
			(at 0 5.311902 90)
			(unlocked yes)
			(layer "Cmts.User")
			(hide yes)
			(effects
				(font
					(size 0.7874 0.5842)
					(thickness 0.1524)
				)
			)
		)
		(property "Device Type" "CONN_HDR_2X4_F_S_SMT-G200-1307A"
			(at 0 4.118102 90)
			(unlocked yes)
			(layer "F.Fab")
			(hide yes)
			(effects
				(font
					(size 0.7874 0.5842)
					(thickness 0.1524)
				)
			)
		)
		(duplicate_pad_numbers_are_jumpers no)
		(fp_line
			(start 4.52755 -3.008884)
			(end 4.52755 3.009138)
			(stroke
				(width 0.1)
				(type default)
			)
			(layer "F.SilkS")
		)
		(fp_line
			(start -4.52755 -3.008884)
			(end 4.52755 -3.008884)
			(stroke
				(width 0.1)
				(type default)
			)
			(layer "F.SilkS")
		)
		(fp_line
			(start 4.52755 3.009138)
			(end -4.52755 3.009138)
			(stroke
				(width 0.1)
				(type default)
			)
			(layer "F.SilkS")
		)
		(fp_line
			(start -4.52755 3.009138)
			(end -4.52755 -3.008884)
			(stroke
				(width 0.1)
				(type default)
			)
			(layer "F.SilkS")
		)
		(fp_rect
			(start -4.78155 -3.262884)
			(end 4.78155 3.263138)
			(stroke
				(width 0)
				(type default)
			)
			(fill no)
			(layer "F.CrtYd")
		)
		(fp_line
			(start 4.27355 -2.06502)
			(end 4.27355 2.06502)
			(stroke
				(width 0.1)
				(type default)
			)
			(layer "F.Fab")
		)
		(fp_line
			(start -4.27355 -2.06502)
			(end 4.27355 -2.06502)
			(stroke
				(width 0.1)
				(type default)
			)
			(layer "F.Fab")
		)
		(fp_line
			(start 4.27355 2.06502)
			(end -4.27355 2.06502)
			(stroke
				(width 0.1)
				(type default)
			)
			(layer "F.Fab")
		)
		(fp_line
			(start -4.27355 2.06502)
			(end -4.27355 -2.06502)
			(stroke
				(width 0.1)
				(type default)
			)
			(layer "F.Fab")
		)
		(fp_text user "8"
			(at -3.218434 -3.962908 0)
			(unlocked yes)
			(layer "F.SilkS")
			(effects
				(font
					(size 0.7874 0.5842)
					(thickness 0.1524)
				)
			)
		)
		(fp_text user "2"
			(at 2.115566 -3.581908 0)
			(unlocked yes)
			(layer "F.SilkS")
			(effects
				(font
					(size 0.7874 0.5842)
					(thickness 0.1524)
				)
			)
		)
		(fp_text user "1"
			(at 3.004566 3.657092 0)
			(unlocked yes)
			(layer "F.SilkS")
			(effects
				(font
					(size 0.7874 0.5842)
					(thickness 0.1524)
				)
			)
		)
		(fp_text user "7"
			(at -2.329434 4.038092 0)
			(unlocked yes)
			(layer "F.SilkS")
			(effects
				(font
					(size 0.7874 0.5842)
					(thickness 0.1524)
				)
			)
		)
		(fp_text user "8"
			(at -3.205734 -2.946908 0)
			(unlocked yes)
			(layer "F.Fab")
			(effects
				(font
					(size 0.7874 0.5842)
					(thickness 0.1524)
				)
			)
		)
		(fp_text user "2"
			(at 3.525266 -2.819908 0)
			(unlocked yes)
			(layer "F.Fab")
			(effects
				(font
					(size 0.7874 0.5842)
					(thickness 0.1524)
				)
			)
		)
		(fp_text user "1"
			(at 3.398266 2.641092 0)
			(unlocked yes)
			(layer "F.Fab")
			(effects
				(font
					(size 0.7874 0.5842)
					(thickness 0.1524)
				)
			)
		)
		(fp_text user "7"
			(at -3.280664 2.932938 0)
			(unlocked yes)
			(layer "F.Fab")
			(effects
				(font
					(size 0.7874 0.5842)
					(thickness 0.1524)
				)
			)
		)
		(pad "1" smd rect
			(at 2.999994 1.637538 90)
			(size 1.016 2.2352)
			(layers "F.Cu" "F.Mask" "F.Paste")
			(net "XP5R0V_VCC_ANT")
		)
		(pad "2" smd rect
			(at 2.999994 -1.637284 90)
			(size 1.016 2.2352)
			(layers "F.Cu" "F.Mask" "F.Paste")
			(net "XP3R3V_GPS")
		)
		(pad "3" smd rect
			(at 0.999998 1.637538 90)
			(size 1.016 2.2352)
			(layers "F.Cu" "F.Mask" "F.Paste")
			(net "GPS_UART_TXD")
		)
		(pad "4" smd rect
			(at 0.999998 -1.637284 90)
			(size 1.016 2.2352)
			(layers "F.Cu" "F.Mask" "F.Paste")
			(net "GPS_RST_N")
		)
		(pad "5" smd rect
			(at -0.999998 1.637538 90)
			(size 1.016 2.2352)
			(layers "F.Cu" "F.Mask" "F.Paste")
			(net "GPS_UART_RXD")
		)
		(pad "6" smd rect
			(at -0.999998 -1.637284 90)
			(size 1.016 2.2352)
			(layers "F.Cu" "F.Mask" "F.Paste")
			(net "GPSTP1_OUT")
		)
		(pad "7" smd rect
			(at -2.999994 1.637538 90)
			(size 1.016 2.2352)
			(layers "F.Cu" "F.Mask" "F.Paste")
			(net "GPSTP2_OUT")
		)
		(pad "8" smd rect
			(at -2.999994 -1.637284 90)
			(size 1.016 2.2352)
			(layers "F.Cu" "F.Mask" "F.Paste")
			(net "SG")
		)
	)
)
